# BASEBOARD_FAB2 (Tioga Pass) — schematic netlist excerpt (pin names and nets, part order shuffled) for the footprints in the layout excerpt that follows; sources: Cadence DE-HDL packaged netlist, KiCad conversion of Wiwynn_Tioga_Pass_MB.brd

R8N1  RES  1.8K 1% CHIP  pkg 0402  page 55 : A = P3V3_STBY ; B = FM_CPU1_PROC_ID1
C25W46  CAP  10UF 16V 10% X6S  pkg 0805  page 149 : A = VCC_D_3V3 ; B = GND
C5G55  CAP_A  22.0UF 4V 20% X6S  pkg 0603V  page 242 : A = PVDDQ_ABC ; B = GND

(kicad_pcb
	(version 20260206)
	(generator "pcbnew")
	(generator_version "10.0")
	(general
		(thickness 1.6)
		(legacy_teardrops no)
	)
	(paper "A4")
	(title_block
		(title "Wiwynn_Tioga_Pass_MB.brd")
		(comment 1 "Tioga Pass / footprints 3613-3615 of 4770")
	)
	(layers
		(0 "F.Cu" signal "TOP")
		(4 "In1.Cu" signal "L2GND")
		(6 "In2.Cu" signal "L3")
		(8 "In3.Cu" signal "L4GND")
		(10 "In4.Cu" signal "L5")
		(12 "In5.Cu" signal "L6GND")
		(14 "In6.Cu" signal "L7VCC")
		(16 "In7.Cu" signal "L8VCC")
		(18 "In8.Cu" signal "L9GND")
		(20 "In9.Cu" signal "L10")
		(22 "In10.Cu" signal "L11GND")
		(24 "In11.Cu" signal "L12")
		(26 "In12.Cu" signal "L13GND")
		(2 "B.Cu" signal "BOTTOM")
		(9 "F.Adhes" user "F.Adhesive")
		(11 "B.Adhes" user "B.Adhesive")
		(13 "F.Paste" user "Package Geometry/Pastemask Top")
		(15 "B.Paste" user "Package Geometry/Pastemask Bottom")
		(5 "F.SilkS" user "Ref Des/Silkscreen Top")
		(7 "B.SilkS" user "Ref Des/Silkscreen Bottom")
		(1 "F.Mask" user "Board Geometry/Soldermask Top")
		(3 "B.Mask" user "Board Geometry/Soldermask Bottom")
		(17 "Dwgs.User" user "User.Drawings")
		(19 "Cmts.User" user "User.Comments")
		(21 "Eco1.User" user "User.Eco1")
		(23 "Eco2.User" user "User.Eco2")
		(25 "Edge.Cuts" user "Board Geometry/Outline")
		(27 "Margin" user)
		(31 "F.CrtYd" user "Package Geometry/Place Bound Top")
		(29 "B.CrtYd" user "Package Geometry/Place Bound Bottom")
		(35 "F.Fab" user "Ref Des/Assembly Top")
		(33 "B.Fab" user "Ref Des/Assembly Bottom")
	)
	(footprint ""
		(layer "B.Cu")
		(at 63.0428 -93.1672 90)
		(property "Reference" "R8N1"
			(at 0 0 90)
			(layer "B.SilkS")
			(hide yes)
			(effects
				(font
					(size 1.27 1.27)
				)
				(justify mirror)
			)
		)
		(property "Value" ""
			(at 0 0 90)
			(layer "B.Fab")
			(effects
				(font
					(size 1.27 1.27)
				)
				(justify mirror)
			)
		)
		(duplicate_pad_numbers_are_jumpers no)
		(fp_poly
			(pts
				(xy 0.2794 -0.1016) (xy -0.2794 -0.1016) (xy -0.2794 0.9906) (xy 0.2794 0.9906)
			)
			(stroke
				(width 0)
				(type default)
			)
			(fill no)
			(layer "B.CrtYd")
		)
		(fp_line
			(start 0.2794 -0.1016)
			(end 0.2794 0.9906)
			(stroke
				(width 0.1)
				(type default)
			)
			(layer "B.Fab")
		)
		(fp_line
			(start -0.2794 -0.1016)
			(end 0.2794 -0.1016)
			(stroke
				(width 0.1)
				(type default)
			)
			(layer "B.Fab")
		)
		(fp_line
			(start 0.2794 0.9906)
			(end -0.2794 0.9906)
			(stroke
				(width 0.1)
				(type default)
			)
			(layer "B.Fab")
		)
		(fp_line
			(start -0.2794 0.9906)
			(end -0.2794 -0.1016)
			(stroke
				(width 0.1)
				(type default)
			)
			(layer "B.Fab")
		)
		(pad "1" smd rect
			(at 0 0 270)
			(size 0.508 0.508)
			(layers "B.Cu" "B.Mask" "B.Paste")
			(net "P3V3_STBY")
		)
		(pad "2" smd rect
			(at 0 0.889 270)
			(size 0.508 0.508)
			(layers "B.Cu" "B.Mask" "B.Paste")
			(net "FM_CPU1_PROC_ID1")
		)
		(zone
			(layer "B.Cu")
			(hatch none 0.5)
			(connect_pads
				(clearance 0)
			)
			(min_thickness 0.25)
			(keepout
				(tracks allowed)
				(vias not_allowed)
				(pads allowed)
				(copperpour not_allowed)
				(footprints allowed)
			)
			(placement
				(enabled no)
				(sheetname "")
			)
			(fill
				(thermal_gap 0.5)
				(thermal_bridge_width 0.5)
				(island_removal_mode 0)
			)
			(polygon
				(pts
					(xy 63.2968 -93.4212) (xy 63.2968 -92.9132) (xy 63.6778 -92.9132) (xy 63.6778 -93.4212)
				)
			)
		)
		(zone
			(layer "B.Cu")
			(hatch none 0.5)
			(connect_pads
				(clearance 0)
			)
			(min_thickness 0.25)
			(keepout
				(tracks not_allowed)
				(vias allowed)
				(pads allowed)
				(copperpour not_allowed)
				(footprints allowed)
			)
			(placement
				(enabled no)
				(sheetname "")
			)
			(fill
				(thermal_gap 0.5)
				(thermal_bridge_width 0.5)
				(island_removal_mode 0)
			)
			(polygon
				(pts
					(xy 63.6778 -93.4212) (xy 63.6778 -92.9132) (xy 63.2968 -92.9132) (xy 63.2968 -93.4212)
				)
			)
		)
	)
	(footprint ""
		(layer "B.Cu")
		(at 413.734504 -48.445674 90)
		(property "Reference" "C25W46"
			(at -1.47828 0.78994 180)
			(unlocked yes)
			(layer "B.SilkS")
			(effects
				(font
					(size 0.4064 0.254)
					(thickness 0.1524)
				)
				(justify mirror)
			)
		)
		(property "Value" ""
			(at 0 0 90)
			(layer "B.Fab")
			(effects
				(font
					(size 1.27 1.27)
				)
				(justify mirror)
			)
		)
		(duplicate_pad_numbers_are_jumpers no)
		(fp_poly
			(pts
				(xy 0.7239 -0.2159) (xy -0.7239 -0.2159) (xy -0.7239 1.9939) (xy 0.7239 1.9939)
			)
			(stroke
				(width 0)
				(type default)
			)
			(fill no)
			(layer "B.CrtYd")
		)
		(fp_line
			(start 0.7239 -0.2159)
			(end 0.7239 1.9939)
			(stroke
				(width 0.1)
				(type default)
			)
			(layer "B.Fab")
		)
		(fp_line
			(start -0.7239 -0.2159)
			(end 0.7239 -0.2159)
			(stroke
				(width 0.1)
				(type default)
			)
			(layer "B.Fab")
		)
		(fp_line
			(start 0.7239 1.9939)
			(end -0.7239 1.9939)
			(stroke
				(width 0.1)
				(type default)
			)
			(layer "B.Fab")
		)
		(fp_line
			(start -0.7239 1.9939)
			(end -0.7239 -0.2159)
			(stroke
				(width 0.1)
				(type default)
			)
			(layer "B.Fab")
		)
		(pad "1" smd rect
			(at 0 0 270)
			(size 1.27 1.016)
			(layers "B.Cu" "B.Mask" "B.Paste")
			(net "VCC_D_3V3")
		)
		(pad "2" smd rect
			(at 0 1.778 270)
			(size 1.27 1.016)
			(layers "B.Cu" "B.Mask" "B.Paste")
			(net "GND")
		)
		(zone
			(layer "B.Cu")
			(hatch none 0.5)
			(connect_pads
				(clearance 0)
			)
			(min_thickness 0.25)
			(keepout
				(tracks not_allowed)
				(vias allowed)
				(pads allowed)
				(copperpour not_allowed)
				(footprints allowed)
			)
			(placement
				(enabled no)
				(sheetname "")
			)
			(fill
				(thermal_gap 0.5)
				(thermal_bridge_width 0.5)
				(island_removal_mode 0)
			)
			(polygon
				(pts
					(xy 414.242504 -49.080674) (xy 414.242504 -47.810674) (xy 415.004504 -47.810674) (xy 415.004504 -49.080674)
				)
			)
		)
	)
	(footprint ""
		(layer "B.Cu")
		(at 266.397232 -3.3528 90)
		(property "Reference" "C5G55"
			(at -1.14681 0.76708 180)
			(unlocked yes)
			(layer "B.SilkS")
			(effects
				(font
					(size 0.7874 0.5842)
					(thickness 0.1524)
				)
				(justify mirror)
			)
		)
		(property "Value" ""
			(at 0 0 90)
			(layer "B.Fab")
			(effects
				(font
					(size 1.27 1.27)
				)
				(justify mirror)
			)
		)
		(duplicate_pad_numbers_are_jumpers no)
		(fp_rect
			(start -0.4953 -0.2032)
			(end 0.4953 1.6002)
			(stroke
				(width 0)
				(type default)
			)
			(fill no)
			(layer "B.CrtYd")
		)
		(fp_line
			(start 0.4953 -0.2032)
			(end -0.4953 -0.2032)
			(stroke
				(width 0.1)
				(type default)
			)
			(layer "B.Fab")
		)
		(fp_line
			(start -0.4953 -0.2032)
			(end -0.4953 1.6002)
			(stroke
				(width 0.1)
				(type default)
			)
			(layer "B.Fab")
		)
		(fp_line
			(start 0.4953 1.6002)
			(end 0.4953 -0.2032)
			(stroke
				(width 0.1)
				(type default)
			)
			(layer "B.Fab")
		)
		(fp_line
			(start -0.4953 1.6002)
			(end 0.4953 1.6002)
			(stroke
				(width 0.1)
				(type default)
			)
			(layer "B.Fab")
		)
		(pad "1" smd rect
			(at 0 0 270)
			(size 0.762 0.889)
			(layers "B.Cu" "B.Mask" "B.Paste")
			(net "PVDDQ_ABC")
		)
		(pad "2" smd rect
			(at 0 1.397 270)
			(size 0.762 0.889)
			(layers "B.Cu" "B.Mask" "B.Paste")
			(net "GND")
		)
		(zone
			(layer "B.Cu")
			(hatch none 0.5)
			(connect_pads
				(clearance 0)
			)
			(min_thickness 0.25)
			(keepout
				(tracks not_allowed)
				(vias allowed)
				(pads allowed)
				(copperpour not_allowed)
				(footprints allowed)
			)
			(placement
				(enabled no)
				(sheetname "")
			)
			(fill
				(thermal_gap 0.5)
				(thermal_bridge_width 0.5)
				(island_removal_mode 0)
			)
			(polygon
				(pts
					(xy 266.841732 -2.9718) (xy 267.349732 -2.9718) (xy 267.349732 -3.7338) (xy 266.841732 -3.7338)
				)
			)
		)
	)
)
